(kicad_pcb
	(version 20221018)
	(generator pcbnew)
	(general
    (thickness 1.7403)
  )
	(paper "A4")
	(title_block
    (title "Data Center RDIMM DDR4 Tester")
    (date "2024-09-30")
    (rev "1.2.4")
		(comment 9 "footprints 347-354 of 690")
	)
	(layers
    (0 "F.Cu" signal)
    (1 "In1.Cu" power)
    (2 "In2.Cu" signal)
    (3 "In3.Cu" power)
    (4 "In4.Cu" power)
    (5 "In5.Cu" signal)
    (6 "In6.Cu" power)
    (7 "In7.Cu" signal)
    (8 "In8.Cu" power)
    (9 "In9.Cu" signal)
    (10 "In10.Cu" power)
    (31 "B.Cu" signal)
    (32 "B.Adhes" user "B.Adhesive")
    (33 "F.Adhes" user "F.Adhesive")
    (34 "B.Paste" user)
    (35 "F.Paste" user)
    (36 "B.SilkS" user "B.Silkscreen")
    (37 "F.SilkS" user "F.Silkscreen")
    (38 "B.Mask" user)
    (39 "F.Mask" user)
    (40 "Dwgs.User" user "User.Drawings")
    (41 "Cmts.User" user "User.Comments")
    (42 "Eco1.User" user "User.Eco1")
    (43 "Eco2.User" user "User.Eco2")
    (44 "Edge.Cuts" user)
    (45 "Margin" user)
    (46 "B.CrtYd" user "B.Courtyard")
    (47 "F.CrtYd" user "F.Courtyard")
    (48 "B.Fab" user)
    (49 "F.Fab" user)
  )
	(footprint "data-center-rdimm-ddr4-tester-footprints:C_0402_1005Metric" (layer "F.Cu")
    (at 158.7 104.475 -90)
    (descr "Capacitor SMD 0402")
    (tags "capacitor SMD 0402")
    (property "Author" "Antmicro")
    (property "DNP" "DNP")
    (property "Dielectric" "X5R")
    (property "License" "Apache-2.0")
    (property "MPN" "GRM155R61H104KE14D")
    (property "Manufacturer" "Murata")
    (property "Sheetfile" "ethernet.kicad_sch")
    (property "Sheetname" "Ethernet")
    (property "Val" "100n")
    (property "Voltage" "50V")
    (property "dnp" "")
    (property "exclude_from_bom" "")
    (property "ki_description" " ")
    (attr exclude_from_pos_files exclude_from_bom)
    (fp_text reference "C290" (at 3.615 -0.37 -90) (layer "F.SilkS")
        (effects (font (size 0.7 0.7) (thickness 0.15)) (justify left bottom))
    )
    (fp_text value "C_100n_0402" (at 0 1.4 -90) (layer "F.Fab") hide
        (effects (font (size 0.7 0.7) (thickness 0.15)) (justify left bottom))
    )
    (fp_text user "${REFERENCE}" (at -0.932 3.168 -90) (layer "F.Fab") hide
        (effects (font (size 0.7 0.7) (thickness 0.15)) (justify left bottom))
    )
    (fp_text user "License: Apache-2.0" (at -0.932 5.17 -90) (layer "F.Fab") hide
        (effects (font (size 0.7 0.7) (thickness 0.15)) (justify left bottom))
    )
    (fp_text user "Author: Antmicro" (at -0.932 4.17 -90) (layer "F.Fab") hide
        (effects (font (size 0.7 0.7) (thickness 0.15)) (justify left bottom))
    )
    (fp_rect (start -0.94 -0.47) (end 0.94 0.47)
      (stroke (width 0.05) (type solid)) (fill none) (layer "F.CrtYd"))
    (fp_rect (start -0.499 -0.249) (end 0.499 0.249)
      (stroke (width 0.15) (type solid)) (fill none) (layer "F.Fab"))
    (pad "1" smd roundrect (at -0.484 0 270) (size 0.59 0.64) (layers "F.Cu" "F.Paste" "F.Mask") (roundrect_rratio 0.25)
      (net 143 "3V3_SYS") (pintype "passive"))
    (pad "2" smd roundrect (at 0.484 0 270) (size 0.59 0.64) (layers "F.Cu" "F.Paste" "F.Mask") (roundrect_rratio 0.25)
      (net 9 "GND") (pintype "passive"))
  )
	(footprint "data-center-rdimm-ddr4-tester-footprints:C_0402_1005Metric" (layer "F.Cu")
    (at 254.71 87.795 180)
    (descr "Capacitor SMD 0402")
    (tags "capacitor SMD 0402")
    (property "Author" "Antmicro")
    (property "Dielectric" "X5R")
    (property "License" "Apache-2.0")
    (property "MPN" "GRM155R61H104KE14D")
    (property "Manufacturer" "Murata")
    (property "Sheetfile" "fmc_hpc.kicad_sch")
    (property "Sheetname" "FMC HPC")
    (property "Val" "100n")
    (property "Voltage" "50V")
    (property "ki_description" " ")
    (attr smd)
    (fp_text reference "C265" (at -0.8 -0.355 180) (layer "F.SilkS")
        (effects (font (size 0.7 0.7) (thickness 0.15)) (justify left bottom))
    )
    (fp_text value "C_100n_0402" (at 0 1.4 180) (layer "F.Fab") hide
        (effects (font (size 0.7 0.7) (thickness 0.15)) (justify left bottom))
    )
    (fp_text user "${REFERENCE}" (at -0.932 3.168 180) (layer "F.Fab") hide
        (effects (font (size 0.7 0.7) (thickness 0.15)) (justify left bottom))
    )
    (fp_text user "License: Apache-2.0" (at -0.932 5.17 180) (layer "F.Fab") hide
        (effects (font (size 0.7 0.7) (thickness 0.15)) (justify left bottom))
    )
    (fp_text user "Author: Antmicro" (at -0.932 4.17 180) (layer "F.Fab") hide
        (effects (font (size 0.7 0.7) (thickness 0.15)) (justify left bottom))
    )
    (fp_rect (start -0.94 -0.47) (end 0.94 0.47)
      (stroke (width 0.05) (type solid)) (fill none) (layer "F.CrtYd"))
    (fp_rect (start -0.499 -0.249) (end 0.499 0.249)
      (stroke (width 0.15) (type solid)) (fill none) (layer "F.Fab"))
    (pad "1" smd roundrect (at -0.484 0 180) (size 0.59 0.64) (layers "F.Cu" "F.Paste" "F.Mask") (roundrect_rratio 0.25)
      (net 440 "/FMC HPC/GTX_TX3_C_P") (pintype "passive"))
    (pad "2" smd roundrect (at 0.484 0 180) (size 0.59 0.64) (layers "F.Cu" "F.Paste" "F.Mask") (roundrect_rratio 0.25)
      (net 450 "GTX_TX3_P") (pintype "passive"))
  )
	(footprint "data-center-rdimm-ddr4-tester-footprints:R_0402_1005Metric" (layer "F.Cu")
    (at 202 124.3)
    (descr "Resistor SMD 0402")
    (tags "resistor SMD 0402")
    (property "Author" "Antmicro")
    (property "License" "Apache-2.0")
    (property "MPN" "CR0402-FX-3300GLF")
    (property "Manufacturer" "Bourns")
    (property "Sheetfile" "interfaces.kicad_sch")
    (property "Sheetname" "Interfaces")
    (property "Tolerance" "1%")
    (property "Val" "330R")
    (property "ki_description" "330R resistor in 0402 package with 1% tolerance")
    (attr smd)
    (fp_text reference "R147" (at 0.78 0.4) (layer "F.SilkS")
        (effects (font (size 0.7 0.7) (thickness 0.15)) (justify left bottom))
    )
    (fp_text value "R_330R_0402" (at 0 1.4) (layer "F.Fab") hide
        (effects (font (size 0.7 0.7) (thickness 0.15)) (justify left bottom))
    )
    (fp_text user "Author: Antmicro" (at -0.95 4.169) (layer "F.Fab") hide
        (effects (font (size 0.7 0.7) (thickness 0.15)) (justify left bottom))
    )
    (fp_text user "${REFERENCE}" (at -0.95 3.168) (layer "F.Fab") hide
        (effects (font (size 0.7 0.7) (thickness 0.15)) (justify left bottom))
    )
    (fp_text user "License: Apache-2.0" (at -0.95 5.169) (layer "F.Fab") hide
        (effects (font (size 0.7 0.7) (thickness 0.15)) (justify left bottom))
    )
    (fp_rect (start -0.93 -0.47) (end 0.93 0.47)
      (stroke (width 0.05) (type solid)) (fill none) (layer "F.CrtYd"))
    (fp_rect (start -0.5 -0.25) (end 0.5 0.25)
      (stroke (width 0.15) (type solid)) (fill none) (layer "F.Fab"))
    (pad "1" smd roundrect (at -0.485 0) (size 0.59 0.64) (layers "F.Cu" "F.Paste" "F.Mask") (roundrect_rratio 0.25)
      (net 9 "GND") (pintype "passive"))
    (pad "2" smd roundrect (at 0.485 0) (size 0.59 0.64) (layers "F.Cu" "F.Paste" "F.Mask") (roundrect_rratio 0.25)
      (net 863 "GND1") (pintype "passive"))
  )
	(footprint "data-center-rdimm-ddr4-tester-footprints:R_0201" (layer "F.Cu")
    (at 157.81 104.29 90)
    (descr "Resistor SMD 0201")
    (tags "resistor SMD 0201")
    (property "Author" "Antmicro")
    (property "License" "Apache-2.0")
    (property "MPN" "CR0201-FX-0R00GLF")
    (property "Manufacturer" "Bourns")
    (property "Sheetfile" "ethernet.kicad_sch")
    (property "Sheetname" "Ethernet")
    (property "Tolerance" "1%")
    (property "Val" "0R")
    (property "ki_description" "0R resistor in 0201 package with 1% tolerance")
    (attr smd)
    (fp_text reference "R100" (at 0.64 0.43 90) (layer "F.SilkS")
        (effects (font (size 0.7 0.7) (thickness 0.15)) (justify left bottom))
    )
    (fp_text value "R_0R_0201" (at 0 1.25 90) (layer "F.Fab") hide
        (effects (font (size 0.7 0.7) (thickness 0.15)) (justify left bottom))
    )
    (fp_text user "License: Apache-2.0" (at -0.71 4.25 90) (layer "F.Fab") hide
        (effects (font (size 0.7 0.7) (thickness 0.15)) (justify left bottom))
    )
    (fp_text user "Author: Antmicro" (at -0.71 5.25 90) (layer "F.Fab") hide
        (effects (font (size 0.7 0.7) (thickness 0.15)) (justify left bottom))
    )
    (fp_text user "${REFERENCE}" (at -0.71 3.25 90) (layer "F.Fab") hide
        (effects (font (size 0.7 0.7) (thickness 0.15)) (justify left bottom))
    )
    (fp_rect (start -0.71 -0.36) (end 0.71 0.36)
      (stroke (width 0.05) (type solid)) (fill none) (layer "F.CrtYd"))
    (fp_rect (start -0.3 -0.15) (end 0.298 0.148)
      (stroke (width 0.15) (type solid)) (fill none) (layer "F.Fab"))
    (pad "" smd roundrect (at -0.346 0 90) (size 0.318 0.36) (layers "F.Paste") (roundrect_rratio 0.25))
    (pad "" smd roundrect (at 0.344 0 90) (size 0.318 0.36) (layers "F.Paste") (roundrect_rratio 0.25))
    (pad "1" smd roundrect (at -0.32 0 90) (size 0.46 0.4) (layers "F.Cu" "F.Mask") (roundrect_rratio 0.25)
      (net 827 "/Ethernet/ETH2_BP_N") (pintype "passive"))
    (pad "2" smd roundrect (at 0.32 0 90) (size 0.46 0.4) (layers "F.Cu" "F.Mask") (roundrect_rratio 0.25)
      (net 172 "/Ethernet/ETH2_N") (pintype "passive"))
  )
	(footprint "data-center-rdimm-ddr4-tester-footprints:R_0402_1005Metric" (layer "F.Cu")
    (at 252.55 127.375 -90)
    (descr "Resistor SMD 0402")
    (tags "resistor SMD 0402")
    (property "Author" "Antmicro")
    (property "License" "Apache-2.0")
    (property "MPN" "CR0402-FX-1002GLF")
    (property "Manufacturer" "Bourns")
    (property "Sheetfile" "fmc_hpc.kicad_sch")
    (property "Sheetname" "FMC HPC")
    (property "Tolerance" "1%")
    (property "Val" "10k")
    (property "ki_description" "10k resistor in 0402 package with 1% tolerance")
    (attr smd)
    (fp_text reference "R154" (at 3.565 -0.57 -90) (layer "F.SilkS")
        (effects (font (size 0.7 0.7) (thickness 0.15)) (justify left bottom))
    )
    (fp_text value "R_10k_0402" (at 0 1.4 -90) (layer "F.Fab") hide
        (effects (font (size 0.7 0.7) (thickness 0.15)) (justify left bottom))
    )
    (fp_text user "Author: Antmicro" (at -0.95 4.169 -90) (layer "F.Fab") hide
        (effects (font (size 0.7 0.7) (thickness 0.15)) (justify left bottom))
    )
    (fp_text user "License: Apache-2.0" (at -0.95 5.169 -90) (layer "F.Fab") hide
        (effects (font (size 0.7 0.7) (thickness 0.15)) (justify left bottom))
    )
    (fp_text user "${REFERENCE}" (at -0.95 3.168 -90) (layer "F.Fab") hide
        (effects (font (size 0.7 0.7) (thickness 0.15)) (justify left bottom))
    )
    (fp_rect (start -0.93 -0.47) (end 0.93 0.47)
      (stroke (width 0.05) (type solid)) (fill none) (layer "F.CrtYd"))
    (fp_rect (start -0.5 -0.25) (end 0.5 0.25)
      (stroke (width 0.15) (type solid)) (fill none) (layer "F.Fab"))
    (pad "1" smd roundrect (at -0.485 0 270) (size 0.59 0.64) (layers "F.Cu" "F.Paste" "F.Mask") (roundrect_rratio 0.25)
      (net 181 "Net-(J5D-PG_{C2M})") (pintype "passive"))
    (pad "2" smd roundrect (at 0.485 0 270) (size 0.59 0.64) (layers "F.Cu" "F.Paste" "F.Mask") (roundrect_rratio 0.25)
      (net 143 "3V3_SYS") (pintype "passive"))
  )
	(footprint "data-center-rdimm-ddr4-tester-footprints:R_0402_1005Metric" (layer "F.Cu")
    (at 254.7 99.5)
    (descr "Resistor SMD 0402")
    (tags "resistor SMD 0402")
    (property "Author" "Antmicro")
    (property "License" "Apache-2.0")
    (property "MPN" "CR0402-FX-33R0GLF")
    (property "Manufacturer" "Bourns")
    (property "Sheetfile" "fmc_hpc.kicad_sch")
    (property "Sheetname" "FMC HPC")
    (property "Tolerance" "1%")
    (property "Val" "33R")
    (property "ki_description" "33R resistor in 0402 package with 1% tolerance")
    (attr smd)
    (fp_text reference "R149" (at -1.74 2.35) (layer "F.SilkS")
        (effects (font (size 0.7 0.7) (thickness 0.15)) (justify left bottom))
    )
    (fp_text value "R_33R_0402" (at 0 1.4) (layer "F.Fab") hide
        (effects (font (size 0.7 0.7) (thickness 0.15)) (justify left bottom))
    )
    (fp_text user "License: Apache-2.0" (at -0.95 5.169) (layer "F.Fab") hide
        (effects (font (size 0.7 0.7) (thickness 0.15)) (justify left bottom))
    )
    (fp_text user "Author: Antmicro" (at -0.95 4.169) (layer "F.Fab") hide
        (effects (font (size 0.7 0.7) (thickness 0.15)) (justify left bottom))
    )
    (fp_text user "${REFERENCE}" (at -0.95 3.168) (layer "F.Fab") hide
        (effects (font (size 0.7 0.7) (thickness 0.15)) (justify left bottom))
    )
    (fp_rect (start -0.93 -0.47) (end 0.93 0.47)
      (stroke (width 0.05) (type solid)) (fill none) (layer "F.CrtYd"))
    (fp_rect (start -0.5 -0.25) (end 0.5 0.25)
      (stroke (width 0.15) (type solid)) (fill none) (layer "F.Fab"))
    (pad "1" smd roundrect (at -0.485 0) (size 0.59 0.64) (layers "F.Cu" "F.Paste" "F.Mask") (roundrect_rratio 0.25)
      (net 898 "/FMC HPC/GTR_REFCLK1_R_N") (pintype "passive"))
    (pad "2" smd roundrect (at 0.485 0) (size 0.59 0.64) (layers "F.Cu" "F.Paste" "F.Mask") (roundrect_rratio 0.25)
      (net 892 "GTR_REFCLK1_C_N") (pintype "passive"))
  )
	(footprint "data-center-rdimm-ddr4-tester-footprints:USB-C_GCT_USB4105-GF-A" (layer "F.Cu")
    (at 148.85 132.988)
    (property "Author" "Antmicro")
    (property "License" "Apache-2.0")
    (property "MPN" "USB4105-GF-A")
    (property "Manufacturer" "GCT")
    (property "Sheetfile" "interfaces.kicad_sch")
    (property "Sheetname" "Interfaces")
    (attr smd)
    (fp_text reference "J9" (at -5.06 -4.558) (layer "F.SilkS")
        (effects (font (size 0.7 0.7) (thickness 0.15)) (justify left bottom))
    )
    (fp_text value "USB-C_USB4105-GF-A" (at 0 5) (layer "F.Fab")
        (effects (font (size 0.7 0.7) (thickness 0.15)) (justify left bottom))
    )
    (fp_text user "Author: Antmicro" (at -4.79 7.853) (layer "F.Fab") hide
        (effects (font (size 0.7 0.7) (thickness 0.15)) (justify left bottom))
    )
    (fp_text user "PCB-EDGE" (at -4.79 5.853) (layer "F.Fab") hide
        (effects (font (size 0.7 0.7) (thickness 0.15)) (justify left bottom))
    )
    (fp_text user "${REFERENCE}" (at -4.79 6.853) (layer "F.Fab") hide
        (effects (font (size 0.7 0.7) (thickness 0.15)) (justify left bottom))
    )
    (fp_text user "License: Apache-2.0" (at -4.79 8.855) (layer "F.Fab") hide
        (effects (font (size 0.7 0.7) (thickness 0.15)) (justify left bottom))
    )
    (fp_line (start -4.79 -1.395) (end -4.79 -0.145)
      (stroke (width 0.15) (type solid)) (layer "F.SilkS"))
    (fp_line (start -4.79 2.575) (end -4.79 3.854)
      (stroke (width 0.15) (type solid)) (layer "F.SilkS"))
    (fp_line (start -4.79 3.854) (end 4.788 3.854)
      (stroke (width 0.15) (type solid)) (layer "F.SilkS"))
    (fp_line (start 4.788 -1.395) (end 4.788 -0.145)
      (stroke (width 0.15) (type solid)) (layer "F.SilkS"))
    (fp_line (start 4.788 3.854) (end 4.788 2.575)
      (stroke (width 0.15) (type solid)) (layer "F.SilkS"))
    (fp_circle (center -3.8 -4.27071) (end -3.75 -4.22071)
      (stroke (width 0.15) (type solid)) (fill solid) (layer "F.SilkS"))
    (fp_rect (start -5.1 -4.4) (end 5.1 3.9)
      (stroke (width 0.05) (type solid)) (fill none) (layer "F.CrtYd"))
    (fp_line (start -4.79 -3.676) (end 4.788 -3.676)
      (stroke (width 0.15) (type solid)) (layer "F.Fab"))
    (fp_line (start -4.79 3.854) (end -4.79 -3.676)
      (stroke (width 0.15) (type solid)) (layer "F.Fab"))
    (fp_line (start -4.702 3.854) (end 4.788 3.854)
      (stroke (width 0.15) (type solid)) (layer "F.Fab"))
    (fp_line (start 4.788 -3.676) (end 4.788 3.854)
      (stroke (width 0.15) (type solid)) (layer "F.Fab"))
    (fp_line (start 4.788 3.854) (end -4.79 3.854)
      (stroke (width 0.15) (type solid)) (layer "F.Fab"))
    (pad "" np_thru_hole circle (at -2.891 -2.426) (size 0.65 0.65) (drill 0.65) (layers "*.Cu" "*.Mask"))
    (pad "" np_thru_hole circle (at 2.89 -2.426) (size 0.65 0.65) (drill 0.65) (layers "*.Cu" "*.Mask"))
    (pad "A1" smd roundrect (at -3.202 -3.5) (size 0.6 1.15) (layers "F.Cu" "F.Paste" "F.Mask") (roundrect_rratio 0.25)
      (net 9 "GND") (pinfunction "GND") (pintype "passive"))
    (pad "A4" smd roundrect (at -2.4 -3.5) (size 0.6 1.15) (layers "F.Cu" "F.Paste" "F.Mask") (roundrect_rratio 0.25)
      (net 853 "VBUS") (pinfunction "VBUS") (pintype "passive"))
    (pad "A5" smd roundrect (at -1.25 -3.5) (size 0.3 1.15) (layers "F.Cu" "F.Paste" "F.Mask") (roundrect_rratio 0.25)
      (net 565 "Net-(J9-CC1)") (pinfunction "CC1") (pintype "bidirectional"))
    (pad "A6" smd roundrect (at -0.25 -3.5) (size 0.3 1.15) (layers "F.Cu" "F.Paste" "F.Mask") (roundrect_rratio 0.25)
      (net 10 "DBG_USB_P") (pinfunction "D+") (pintype "bidirectional"))
    (pad "A7" smd roundrect (at 0.248 -3.5) (size 0.3 1.15) (layers "F.Cu" "F.Paste" "F.Mask") (roundrect_rratio 0.25)
      (net 11 "DBG_USB_N") (pinfunction "D-") (pintype "bidirectional"))
    (pad "A8" smd roundrect (at 1.249 -3.5) (size 0.3 1.15) (layers "F.Cu" "F.Paste" "F.Mask") (roundrect_rratio 0.25)
      (net 566 "unconnected-(J9-SBU1-PadA8)") (pinfunction "SBU1") (pintype "bidirectional+no_connect"))
    (pad "A9" smd roundrect (at 2.398 -3.5) (size 0.6 1.15) (layers "F.Cu" "F.Paste" "F.Mask") (roundrect_rratio 0.25)
      (net 853 "VBUS") (pinfunction "VBUS") (pintype "passive"))
    (pad "A12" smd roundrect (at 3.2 -3.5) (size 0.6 1.15) (layers "F.Cu" "F.Paste" "F.Mask") (roundrect_rratio 0.25)
      (net 9 "GND") (pinfunction "GND") (pintype "passive"))
    (pad "B1" smd roundrect (at 3.2 -3.5) (size 0.6 1.15) (layers "F.Cu" "F.Paste" "F.Mask") (roundrect_rratio 0.25)
      (net 9 "GND") (pinfunction "GND") (pintype "passive"))
    (pad "B4" smd roundrect (at 2.398 -3.5) (size 0.6 1.15) (layers "F.Cu" "F.Paste" "F.Mask") (roundrect_rratio 0.25)
      (net 853 "VBUS") (pinfunction "VBUS") (pintype "passive"))
    (pad "B5" smd roundrect (at 1.749 -3.5) (size 0.3 1.15) (layers "F.Cu" "F.Paste" "F.Mask") (roundrect_rratio 0.25)
      (net 569 "Net-(J9-CC2)") (pinfunction "CC2") (pintype "bidirectional"))
    (pad "B6" smd roundrect (at 0.748 -3.5) (size 0.3 1.15) (layers "F.Cu" "F.Paste" "F.Mask") (roundrect_rratio 0.25)
      (net 10 "DBG_USB_P") (pinfunction "D+") (pintype "passive"))
    (pad "B7" smd roundrect (at -0.75 -3.5) (size 0.3 1.15) (layers "F.Cu" "F.Paste" "F.Mask") (roundrect_rratio 0.25)
      (net 11 "DBG_USB_N") (pinfunction "D-") (pintype "passive"))
    (pad "B8" smd roundrect (at -1.75 -3.5) (size 0.3 1.15) (layers "F.Cu" "F.Paste" "F.Mask") (roundrect_rratio 0.25)
      (net 570 "unconnected-(J9-SBU2-PadB8)") (pinfunction "SBU2") (pintype "bidirectional+no_connect"))
    (pad "B9" smd roundrect (at -2.4 -3.5) (size 0.6 1.15) (layers "F.Cu" "F.Paste" "F.Mask") (roundrect_rratio 0.25)
      (net 853 "VBUS") (pinfunction "VBUS") (pintype "passive"))
    (pad "B12" smd roundrect (at -3.202 -3.5) (size 0.6 1.15) (layers "F.Cu" "F.Paste" "F.Mask") (roundrect_rratio 0.25)
      (net 9 "GND") (pinfunction "GND") (pintype "passive"))
    (pad "SH" thru_hole oval (at -4.321 -2.926) (size 1.05 2.1) (drill oval 0.6 1.7) (layers "*.Cu" "*.Mask")
      (net 862 "GNDS") (pinfunction "SHIELD") (pintype "passive"))
    (pad "SH" thru_hole oval (at -4.321 1.255) (size 1 2) (drill oval 0.6 1.4) (layers "*.Cu" "*.Mask")
      (net 862 "GNDS") (pinfunction "SHIELD") (pintype "passive"))
    (pad "SH" thru_hole oval (at 4.32 -2.926) (size 1.05 2.1) (drill oval 0.6 1.7) (layers "*.Cu" "*.Mask")
      (net 862 "GNDS") (pinfunction "SHIELD") (pintype "passive"))
    (pad "SH" thru_hole oval (at 4.32 1.255) (size 1 2) (drill oval 0.6 1.4) (layers "*.Cu" "*.Mask")
      (net 862 "GNDS") (pinfunction "SHIELD") (pintype "passive"))
  )
	(footprint "data-center-rdimm-ddr4-tester-footprints:TP_SMD_0.75mm" (layer "F.Cu")
    (at 250.675 123.4742)
    (property "Author" "Antmicro")
    (property "License" "Apache-2.0")
    (property "MPN" "")
    (property "Manufacturer" "")
    (property "Sheetfile" "fmc_hpc.kicad_sch")
    (property "Sheetname" "FMC HPC")
    (property "ki_description" "Test Point 0.75mm")
    (attr exclude_from_pos_files)
    (fp_text reference "TP19" (at 0.515 0.3558) (layer "F.SilkS")
        (effects (font (size 0.7 0.7) (thickness 0.15)) (justify left bottom))
    )
    (fp_text value "TP_0.75mm_SMD" (at 0 1.2) (layer "F.Fab") hide
        (effects (font (size 0.7 0.7) (thickness 0.15)) (justify left bottom))
    )
    (fp_text user "License: Apache-2.0" (at -0.4 5.101) (layer "F.Fab") hide
        (effects (font (size 0.7 0.7) (thickness 0.15)) (justify left bottom))
    )
    (fp_text user "${REFERENCE}" (at -0.4 2.7) (layer "F.Fab") hide
        (effects (font (size 0.7 0.7) (thickness 0.15)) (justify left bottom))
    )
    (fp_text user "Author: Antmicro" (at -0.4 3.901) (layer "F.Fab") hide
        (effects (font (size 0.7 0.7) (thickness 0.15)) (justify left bottom))
    )
    (pad "1" smd circle (at 0 0) (size 0.75 0.75) (layers "F.Cu" "F.Mask")
      (net 405 "Net-(J5C-PG_{M2C})") (pinfunction "1") (pintype "passive"))
  )
)
